# S9S_MB_2U (Grand Teton) — schematic netlist excerpt (pin names and nets, part order shuffled) for the footprints in the layout excerpt that follows; sources: Cadence DE-HDL packaged netlist, KiCad conversion of 03242023_DA0F0TMBIJ0_F0T_Motherboard_J_brd_V01_OCP.brd

C174  Q_CAP  0.1UF 25V 10% X7R  pkg 0402  page 231 : A = P3V3_AUX ; B = GND
C938  Q_CAP_DIFFBUS  DIFF BUS_0.22UF 6.3V 20% X6S  pkg C0201  page 173 : \1\ = P5E_CPU0_PE2_TX_C_DN<13> ; \2\ = P5E_CPU0_PE2_TX_DN<13>
C290  Q_CAP  22UF 4V 20% X6S  pkg C0402  page 77 : A = PVCCIN_CPU1 ; B = GND

(kicad_pcb
	(version 20260206)
	(generator "pcbnew")
	(generator_version "10.0")
	(general
		(thickness 1.6)
		(legacy_teardrops no)
	)
	(paper "A4")
	(title_block
		(title "03242023_DA0F0TMBIJ0_F0T_Motherboard_J_brd_V01_OCP.brd")
		(comment 1 "Grand Teton / footprints 3841-3843 of 6105")
	)
	(layers
		(0 "F.Cu" signal "TOP")
		(4 "In1.Cu" signal "GND")
		(6 "In2.Cu" signal "IN1")
		(8 "In3.Cu" signal "GND1")
		(10 "In4.Cu" signal "IN2")
		(12 "In5.Cu" signal "GND2")
		(14 "In6.Cu" signal "IN3")
		(16 "In7.Cu" signal "GND3")
		(18 "In8.Cu" signal "VCC")
		(20 "In9.Cu" signal "VCC1")
		(22 "In10.Cu" signal "GND4")
		(24 "In11.Cu" signal "IN4")
		(26 "In12.Cu" signal "GND5")
		(28 "In13.Cu" signal "IN5")
		(30 "In14.Cu" signal "GND6")
		(32 "In15.Cu" signal "IN6")
		(34 "In16.Cu" signal "GND7")
		(2 "B.Cu" signal "BOTTOM")
		(9 "F.Adhes" user "F.Adhesive")
		(11 "B.Adhes" user "B.Adhesive")
		(13 "F.Paste" user "Package Geometry/Pastemask Top")
		(15 "B.Paste" user "Package Geometry/Pastemask Bottom")
		(5 "F.SilkS" user "Ref Des/Silkscreen Top")
		(7 "B.SilkS" user "Ref Des/Silkscreen Bottom")
		(1 "F.Mask" user "Board Geometry/Soldermask Top")
		(3 "B.Mask" user "Board Geometry/Soldermask Bottom")
		(17 "Dwgs.User" user "User.Drawings")
		(19 "Cmts.User" user "User.Comments")
		(21 "Eco1.User" user "User.Eco1")
		(23 "Eco2.User" user "User.Eco2")
		(25 "Edge.Cuts" user "Board Geometry/Outline")
		(27 "Margin" user)
		(31 "F.CrtYd" user "Package Geometry/Place Bound Top")
		(29 "B.CrtYd" user "Package Geometry/Place Bound Bottom")
		(35 "F.Fab" user "Ref Des/Assembly Top")
		(33 "B.Fab" user "Ref Des/Assembly Bottom")
	)
	(footprint ""
		(layer "F.Cu")
		(at 378.43841 -402.371052 -90)
		(property "Reference" "C938"
			(at 0 0 270)
			(layer "F.SilkS")
			(hide yes)
			(effects
				(font
					(size 1.27 1.27)
				)
			)
		)
		(property "Value" ""
			(at 0 0 270)
			(layer "F.Fab")
			(effects
				(font
					(size 1.27 1.27)
				)
			)
		)
		(duplicate_pad_numbers_are_jumpers no)
		(fp_line
			(start -0.299974 0.150114)
			(end -0.299974 -0.150114)
			(stroke
				(width 0.1)
				(type default)
			)
			(layer "F.Fab")
		)
		(fp_line
			(start 0.299974 0.150114)
			(end -0.299974 0.150114)
			(stroke
				(width 0.1)
				(type default)
			)
			(layer "F.Fab")
		)
		(fp_line
			(start -0.299974 -0.150114)
			(end 0.299974 -0.150114)
			(stroke
				(width 0.1)
				(type default)
			)
			(layer "F.Fab")
		)
		(fp_line
			(start 0.299974 -0.150114)
			(end 0.299974 0.150114)
			(stroke
				(width 0.1)
				(type default)
			)
			(layer "F.Fab")
		)
		(pad "1" smd rect
			(at -0.2667 0 270)
			(size 0.3048 0.381)
			(layers "F.Cu" "F.Mask" "F.Paste")
			(net "P5E_CPU0_PE2_TX_C_DN<13>")
		)
		(pad "2" smd rect
			(at 0.2667 0 270)
			(size 0.3048 0.381)
			(layers "F.Cu" "F.Mask" "F.Paste")
			(net "P5E_CPU0_PE2_TX_DN<13>")
		)
	)
	(footprint ""
		(layer "F.Cu")
		(at 117.526816 -241.97691 -90)
		(property "Reference" "C290"
			(at 0 0 270)
			(layer "F.SilkS")
			(hide yes)
			(effects
				(font
					(size 1.27 1.27)
				)
			)
		)
		(property "Value" ""
			(at 0 0 270)
			(layer "F.Fab")
			(effects
				(font
					(size 1.27 1.27)
				)
			)
		)
		(duplicate_pad_numbers_are_jumpers no)
		(fp_line
			(start -0.7874 0.4064)
			(end -0.7874 -0.4064)
			(stroke
				(width 0.1524)
				(type default)
			)
			(layer "F.SilkS")
		)
		(fp_line
			(start 0.7874 0.4064)
			(end -0.7874 0.4064)
			(stroke
				(width 0.1524)
				(type default)
			)
			(layer "F.SilkS")
		)
		(fp_line
			(start -0.7874 -0.4064)
			(end 0.7874 -0.4064)
			(stroke
				(width 0.1524)
				(type default)
			)
			(layer "F.SilkS")
		)
		(fp_line
			(start 0.7874 -0.4064)
			(end 0.7874 0.4064)
			(stroke
				(width 0.1524)
				(type default)
			)
			(layer "F.SilkS")
		)
		(fp_line
			(start -0.67945 0.3048)
			(end -0.67945 -0.305054)
			(stroke
				(width 0.1)
				(type default)
			)
			(layer "F.Fab")
		)
		(fp_line
			(start -0.12065 0.3048)
			(end -0.67945 0.3048)
			(stroke
				(width 0.1)
				(type default)
			)
			(layer "F.Fab")
		)
		(fp_line
			(start 0.120396 0.3048)
			(end 0.120396 0.2794)
			(stroke
				(width 0.1)
				(type default)
			)
			(layer "F.Fab")
		)
		(fp_line
			(start 0.67945 0.3048)
			(end 0.120396 0.3048)
			(stroke
				(width 0.1)
				(type default)
			)
			(layer "F.Fab")
		)
		(fp_line
			(start -0.12065 0.2794)
			(end -0.12065 0.3048)
			(stroke
				(width 0.1)
				(type default)
			)
			(layer "F.Fab")
		)
		(fp_line
			(start 0.120396 0.2794)
			(end -0.12065 0.2794)
			(stroke
				(width 0.1)
				(type default)
			)
			(layer "F.Fab")
		)
		(fp_line
			(start -0.12065 -0.2794)
			(end 0.12065 -0.2794)
			(stroke
				(width 0.1)
				(type default)
			)
			(layer "F.Fab")
		)
		(fp_line
			(start 0.12065 -0.2794)
			(end 0.12065 -0.3048)
			(stroke
				(width 0.1)
				(type default)
			)
			(layer "F.Fab")
		)
		(fp_line
			(start 0.12065 -0.3048)
			(end 0.67945 -0.3048)
			(stroke
				(width 0.1)
				(type default)
			)
			(layer "F.Fab")
		)
		(fp_line
			(start 0.67945 -0.3048)
			(end 0.67945 0.3048)
			(stroke
				(width 0.1)
				(type default)
			)
			(layer "F.Fab")
		)
		(fp_line
			(start -0.67945 -0.305054)
			(end -0.12065 -0.305054)
			(stroke
				(width 0.1)
				(type default)
			)
			(layer "F.Fab")
		)
		(fp_line
			(start -0.12065 -0.305054)
			(end -0.12065 -0.2794)
			(stroke
				(width 0.1)
				(type default)
			)
			(layer "F.Fab")
		)
		(pad "1" smd circle
			(at -0.40005 0 270)
			(size 0 0)
			(layers "F.Cu" "F.Mask" "F.Paste")
			(net "PVCCIN_CPU1")
		)
		(pad "2" smd circle
			(at 0.40005 0 270)
			(size 0 0)
			(layers "F.Cu" "F.Mask" "F.Paste")
			(net "GND")
		)
	)
	(footprint ""
		(layer "F.Cu")
		(at 125.124972 -139.178538)
		(property "Reference" "C174"
			(at 0 0 0)
			(layer "F.SilkS")
			(hide yes)
			(effects
				(font
					(size 1.27 1.27)
				)
			)
		)
		(property "Value" ""
			(at 0 0 0)
			(layer "F.Fab")
			(effects
				(font
					(size 1.27 1.27)
				)
			)
		)
		(duplicate_pad_numbers_are_jumpers no)
		(fp_line
			(start -0.7874 -0.4064)
			(end 0.7874 -0.4064)
			(stroke
				(width 0.1524)
				(type default)
			)
			(layer "F.SilkS")
		)
		(fp_line
			(start -0.7874 0.4064)
			(end -0.7874 -0.4064)
			(stroke
				(width 0.1524)
				(type default)
			)
			(layer "F.SilkS")
		)
		(fp_line
			(start 0.7874 -0.4064)
			(end 0.7874 0.4064)
			(stroke
				(width 0.1524)
				(type default)
			)
			(layer "F.SilkS")
		)
		(fp_line
			(start 0.7874 0.4064)
			(end -0.7874 0.4064)
			(stroke
				(width 0.1524)
				(type default)
			)
			(layer "F.SilkS")
		)
		(fp_line
			(start -0.67945 -0.305054)
			(end -0.12065 -0.305054)
			(stroke
				(width 0.1)
				(type default)
			)
			(layer "F.Fab")
		)
		(fp_line
			(start -0.67945 0.3048)
			(end -0.67945 -0.305054)
			(stroke
				(width 0.1)
				(type default)
			)
			(layer "F.Fab")
		)
		(fp_line
			(start -0.12065 -0.305054)
			(end -0.12065 -0.2794)
			(stroke
				(width 0.1)
				(type default)
			)
			(layer "F.Fab")
		)
		(fp_line
			(start -0.12065 -0.2794)
			(end 0.12065 -0.2794)
			(stroke
				(width 0.1)
				(type default)
			)
			(layer "F.Fab")
		)
		(fp_line
			(start -0.12065 0.2794)
			(end -0.12065 0.3048)
			(stroke
				(width 0.1)
				(type default)
			)
			(layer "F.Fab")
		)
		(fp_line
			(start -0.12065 0.3048)
			(end -0.67945 0.3048)
			(stroke
				(width 0.1)
				(type default)
			)
			(layer "F.Fab")
		)
		(fp_line
			(start 0.120396 0.2794)
			(end -0.12065 0.2794)
			(stroke
				(width 0.1)
				(type default)
			)
			(layer "F.Fab")
		)
		(fp_line
			(start 0.120396 0.3048)
			(end 0.120396 0.2794)
			(stroke
				(width 0.1)
				(type default)
			)
			(layer "F.Fab")
		)
		(fp_line
			(start 0.12065 -0.3048)
			(end 0.67945 -0.3048)
			(stroke
				(width 0.1)
				(type default)
			)
			(layer "F.Fab")
		)
		(fp_line
			(start 0.12065 -0.2794)
			(end 0.12065 -0.3048)
			(stroke
				(width 0.1)
				(type default)
			)
			(layer "F.Fab")
		)
		(fp_line
			(start 0.67945 -0.3048)
			(end 0.67945 0.3048)
			(stroke
				(width 0.1)
				(type default)
			)
			(layer "F.Fab")
		)
		(fp_line
			(start 0.67945 0.3048)
			(end 0.120396 0.3048)
			(stroke
				(width 0.1)
				(type default)
			)
			(layer "F.Fab")
		)
		(pad "1" smd circle
			(at -0.40005 0)
			(size 0 0)
			(layers "F.Cu" "F.Mask" "F.Paste")
			(net "P3V3_AUX")
		)
		(pad "2" smd circle
			(at 0.40005 0)
			(size 0 0)
			(layers "F.Cu" "F.Mask" "F.Paste")
			(net "GND")
		)
	)
)
